# SCM (Grand Teton) — schematic netlist excerpt (pin names and nets, part order shuffled) for the footprints in the layout excerpt that follows; sources: Cadence DE-HDL packaged netlist, KiCad conversion of 12092022_DA0F0TMDCD0_F0T_Management_Board_D_brd_V3_OCP.brd

R900  Q_RES  0 5% CHIP  pkg 0402LF  page 31 : A = UART_BIC_DBG_TX ; B = UART_BIC_DBG_TX_R
R528  Q_RES  0 5% CHIP  pkg 0402LF  page 15 : A = USB_HOST_BMC_B_R_DN ; B = USB_HOST_BMC_B_DN

(kicad_pcb
	(version 20260206)
	(generator "pcbnew")
	(generator_version "10.0")
	(general
		(thickness 1.6)
		(legacy_teardrops no)
	)
	(paper "A4")
	(title_block
		(title "12092022_DA0F0TMDCD0_F0T_Management_Board_D_brd_V3_OCP.brd")
		(comment 1 "Grand Teton / footprints 11-12 of 1440")
	)
	(layers
		(0 "F.Cu" signal "TOP")
		(4 "In1.Cu" signal "GND")
		(6 "In2.Cu" signal "IN1")
		(8 "In3.Cu" signal "GND1")
		(10 "In4.Cu" signal "IN2")
		(12 "In5.Cu" signal "VCC")
		(14 "In6.Cu" signal "VCC1")
		(16 "In7.Cu" signal "IN3")
		(18 "In8.Cu" signal "GND2")
		(20 "In9.Cu" signal "IN4")
		(22 "In10.Cu" signal "GND3")
		(2 "B.Cu" signal "BOTTOM")
		(9 "F.Adhes" user "F.Adhesive")
		(11 "B.Adhes" user "B.Adhesive")
		(13 "F.Paste" user "Package Geometry/Pastemask Top")
		(15 "B.Paste" user "Package Geometry/Pastemask Bottom")
		(5 "F.SilkS" user "Ref Des/Silkscreen Top")
		(7 "B.SilkS" user "Ref Des/Silkscreen Bottom")
		(1 "F.Mask" user "Board Geometry/Soldermask Top")
		(3 "B.Mask" user "Board Geometry/Soldermask Bottom")
		(17 "Dwgs.User" user "User.Drawings")
		(19 "Cmts.User" user "User.Comments")
		(21 "Eco1.User" user "User.Eco1")
		(23 "Eco2.User" user "User.Eco2")
		(25 "Edge.Cuts" user "Board Geometry/Outline")
		(27 "Margin" user)
		(31 "F.CrtYd" user "Package Geometry/Place Bound Top")
		(29 "B.CrtYd" user "Package Geometry/Place Bound Bottom")
		(35 "F.Fab" user "Ref Des/Assembly Top")
		(33 "B.Fab" user "Ref Des/Assembly Bottom")
	)
	(footprint ""
		(layer "F.Cu")
		(at 18.6436 -56.1848 90)
		(property "Reference" "R900"
			(at 0 0 90)
			(layer "F.SilkS")
			(hide yes)
			(effects
				(font
					(size 1.27 1.27)
				)
			)
		)
		(property "Value" ""
			(at 0 0 90)
			(layer "F.Fab")
			(effects
				(font
					(size 1.27 1.27)
				)
			)
		)
		(duplicate_pad_numbers_are_jumpers no)
		(fp_line
			(start 0.7874 -0.4064)
			(end 0.7874 0.4064)
			(stroke
				(width 0.1524)
				(type default)
			)
			(layer "F.SilkS")
		)
		(fp_line
			(start -0.7874 -0.4064)
			(end 0.7874 -0.4064)
			(stroke
				(width 0.1524)
				(type default)
			)
			(layer "F.SilkS")
		)
		(fp_line
			(start 0.7874 0.4064)
			(end -0.7874 0.4064)
			(stroke
				(width 0.1524)
				(type default)
			)
			(layer "F.SilkS")
		)
		(fp_line
			(start -0.7874 0.4064)
			(end -0.7874 -0.4064)
			(stroke
				(width 0.1524)
				(type default)
			)
			(layer "F.SilkS")
		)
		(fp_line
			(start -0.12065 -0.305054)
			(end -0.12065 -0.2794)
			(stroke
				(width 0.1)
				(type default)
			)
			(layer "F.Fab")
		)
		(fp_line
			(start -0.67945 -0.305054)
			(end -0.12065 -0.305054)
			(stroke
				(width 0.1)
				(type default)
			)
			(layer "F.Fab")
		)
		(fp_line
			(start 0.67945 -0.3048)
			(end 0.67945 0.3048)
			(stroke
				(width 0.1)
				(type default)
			)
			(layer "F.Fab")
		)
		(fp_line
			(start 0.12065 -0.3048)
			(end 0.67945 -0.3048)
			(stroke
				(width 0.1)
				(type default)
			)
			(layer "F.Fab")
		)
		(fp_line
			(start 0.12065 -0.2794)
			(end 0.12065 -0.3048)
			(stroke
				(width 0.1)
				(type default)
			)
			(layer "F.Fab")
		)
		(fp_line
			(start -0.12065 -0.2794)
			(end 0.12065 -0.2794)
			(stroke
				(width 0.1)
				(type default)
			)
			(layer "F.Fab")
		)
		(fp_line
			(start 0.120396 0.2794)
			(end -0.12065 0.2794)
			(stroke
				(width 0.1)
				(type default)
			)
			(layer "F.Fab")
		)
		(fp_line
			(start -0.12065 0.2794)
			(end -0.12065 0.3048)
			(stroke
				(width 0.1)
				(type default)
			)
			(layer "F.Fab")
		)
		(fp_line
			(start 0.67945 0.3048)
			(end 0.120396 0.3048)
			(stroke
				(width 0.1)
				(type default)
			)
			(layer "F.Fab")
		)
		(fp_line
			(start 0.120396 0.3048)
			(end 0.120396 0.2794)
			(stroke
				(width 0.1)
				(type default)
			)
			(layer "F.Fab")
		)
		(fp_line
			(start -0.12065 0.3048)
			(end -0.67945 0.3048)
			(stroke
				(width 0.1)
				(type default)
			)
			(layer "F.Fab")
		)
		(fp_line
			(start -0.67945 0.3048)
			(end -0.67945 -0.305054)
			(stroke
				(width 0.1)
				(type default)
			)
			(layer "F.Fab")
		)
		(pad "1" smd circle
			(at -0.40005 0 90)
			(size 0 0)
			(layers "F.Cu" "F.Mask" "F.Paste")
			(net "UART_BIC_DBG_TX")
		)
		(pad "2" smd circle
			(at 0.40005 0 90)
			(size 0 0)
			(layers "F.Cu" "F.Mask" "F.Paste")
			(net "UART_BIC_DBG_TX_R")
		)
	)
	(footprint ""
		(layer "F.Cu")
		(at 63.553848 -34.870898 -90)
		(property "Reference" "R528"
			(at 0 0 270)
			(layer "F.SilkS")
			(hide yes)
			(effects
				(font
					(size 1.27 1.27)
				)
			)
		)
		(property "Value" ""
			(at 0 0 270)
			(layer "F.Fab")
			(effects
				(font
					(size 1.27 1.27)
				)
			)
		)
		(duplicate_pad_numbers_are_jumpers no)
		(fp_line
			(start 0.420878 0.4064)
			(end -0.122682 0.4064)
			(stroke
				(width 0.1524)
				(type default)
			)
			(layer "F.SilkS")
		)
		(fp_line
			(start -0.7874 0.036068)
			(end -0.7874 -0.4064)
			(stroke
				(width 0.1524)
				(type default)
			)
			(layer "F.SilkS")
		)
		(fp_line
			(start -0.7874 -0.4064)
			(end 0.7874 -0.4064)
			(stroke
				(width 0.1524)
				(type default)
			)
			(layer "F.SilkS")
		)
		(fp_line
			(start 0.7874 -0.4064)
			(end 0.7874 0.084328)
			(stroke
				(width 0.1524)
				(type default)
			)
			(layer "F.SilkS")
		)
		(fp_line
			(start -0.67945 0.3048)
			(end -0.67945 -0.305054)
			(stroke
				(width 0.1)
				(type default)
			)
			(layer "F.Fab")
		)
		(fp_line
			(start -0.12065 0.3048)
			(end -0.67945 0.3048)
			(stroke
				(width 0.1)
				(type default)
			)
			(layer "F.Fab")
		)
		(fp_line
			(start 0.120396 0.3048)
			(end 0.120396 0.2794)
			(stroke
				(width 0.1)
				(type default)
			)
			(layer "F.Fab")
		)
		(fp_line
			(start 0.67945 0.3048)
			(end 0.120396 0.3048)
			(stroke
				(width 0.1)
				(type default)
			)
			(layer "F.Fab")
		)
		(fp_line
			(start -0.12065 0.2794)
			(end -0.12065 0.3048)
			(stroke
				(width 0.1)
				(type default)
			)
			(layer "F.Fab")
		)
		(fp_line
			(start 0.120396 0.2794)
			(end -0.12065 0.2794)
			(stroke
				(width 0.1)
				(type default)
			)
			(layer "F.Fab")
		)
		(fp_line
			(start -0.12065 -0.2794)
			(end 0.12065 -0.2794)
			(stroke
				(width 0.1)
				(type default)
			)
			(layer "F.Fab")
		)
		(fp_line
			(start 0.12065 -0.2794)
			(end 0.12065 -0.3048)
			(stroke
				(width 0.1)
				(type default)
			)
			(layer "F.Fab")
		)
		(fp_line
			(start 0.12065 -0.3048)
			(end 0.67945 -0.3048)
			(stroke
				(width 0.1)
				(type default)
			)
			(layer "F.Fab")
		)
		(fp_line
			(start 0.67945 -0.3048)
			(end 0.67945 0.3048)
			(stroke
				(width 0.1)
				(type default)
			)
			(layer "F.Fab")
		)
		(fp_line
			(start -0.67945 -0.305054)
			(end -0.12065 -0.305054)
			(stroke
				(width 0.1)
				(type default)
			)
			(layer "F.Fab")
		)
		(fp_line
			(start -0.12065 -0.305054)
			(end -0.12065 -0.2794)
			(stroke
				(width 0.1)
				(type default)
			)
			(layer "F.Fab")
		)
		(pad "1" smd circle
			(at -0.40005 0 270)
			(size 0 0)
			(layers "F.Cu" "F.Mask" "F.Paste")
			(net "USB_HOST_BMC_B_R_DN")
		)
		(pad "2" smd circle
			(at 0.40005 0 270)
			(size 0 0)
			(layers "F.Cu" "F.Mask" "F.Paste")
			(net "USB_HOST_BMC_B_DN")
		)
	)
)
